(kicad_pcb
	(version 20260206)
	(generator "pcbnew")
	(generator_version "10.0")
	(general
		(thickness 1.6)
		(legacy_teardrops no)
	)
	(paper "A4")
	(title_block
		(title "03242023_DA0F0TMBIJ0_F0T_Motherboard_J_brd_V01_OCP.brd")
		(comment 1 "Grand Teton / footprints 3281-3287 of 6105")
	)
	(layers
		(0 "F.Cu" signal "TOP")
		(4 "In1.Cu" signal "GND")
		(6 "In2.Cu" signal "IN1")
		(8 "In3.Cu" signal "GND1")
		(10 "In4.Cu" signal "IN2")
		(12 "In5.Cu" signal "GND2")
		(14 "In6.Cu" signal "IN3")
		(16 "In7.Cu" signal "GND3")
		(18 "In8.Cu" signal "VCC")
		(20 "In9.Cu" signal "VCC1")
		(22 "In10.Cu" signal "GND4")
		(24 "In11.Cu" signal "IN4")
		(26 "In12.Cu" signal "GND5")
		(28 "In13.Cu" signal "IN5")
		(30 "In14.Cu" signal "GND6")
		(32 "In15.Cu" signal "IN6")
		(34 "In16.Cu" signal "GND7")
		(2 "B.Cu" signal "BOTTOM")
		(9 "F.Adhes" user "F.Adhesive")
		(11 "B.Adhes" user "B.Adhesive")
		(13 "F.Paste" user "Package Geometry/Pastemask Top")
		(15 "B.Paste" user "Package Geometry/Pastemask Bottom")
		(5 "F.SilkS" user "Ref Des/Silkscreen Top")
		(7 "B.SilkS" user "Ref Des/Silkscreen Bottom")
		(1 "F.Mask" user "Board Geometry/Soldermask Top")
		(3 "B.Mask" user "Board Geometry/Soldermask Bottom")
		(17 "Dwgs.User" user "User.Drawings")
		(19 "Cmts.User" user "User.Comments")
		(21 "Eco1.User" user "User.Eco1")
		(23 "Eco2.User" user "User.Eco2")
		(25 "Edge.Cuts" user "Board Geometry/Outline")
		(27 "Margin" user)
		(31 "F.CrtYd" user "Package Geometry/Place Bound Top")
		(29 "B.CrtYd" user "Package Geometry/Place Bound Bottom")
		(35 "F.Fab" user "Ref Des/Assembly Top")
		(33 "B.Fab" user "Ref Des/Assembly Bottom")
	)
	(footprint ""
		(layer "F.Cu")
		(at 446.851024 -175.956468)
		(property "Reference" "PC1276"
			(at 0 0 0)
			(layer "F.SilkS")
			(hide yes)
			(effects
				(font
					(size 1.27 1.27)
				)
			)
		)
		(property "Value" ""
			(at 0 0 0)
			(layer "F.Fab")
			(effects
				(font
					(size 1.27 1.27)
				)
			)
		)
		(duplicate_pad_numbers_are_jumpers no)
		(fp_line
			(start -0.7874 -0.4064)
			(end 0.7874 -0.4064)
			(stroke
				(width 0.1524)
				(type default)
			)
			(layer "F.SilkS")
		)
		(fp_line
			(start -0.7874 0.4064)
			(end -0.7874 -0.4064)
			(stroke
				(width 0.1524)
				(type default)
			)
			(layer "F.SilkS")
		)
		(fp_line
			(start 0.7874 -0.4064)
			(end 0.7874 0.4064)
			(stroke
				(width 0.1524)
				(type default)
			)
			(layer "F.SilkS")
		)
		(fp_line
			(start 0.7874 0.4064)
			(end -0.7874 0.4064)
			(stroke
				(width 0.1524)
				(type default)
			)
			(layer "F.SilkS")
		)
		(fp_line
			(start -0.67945 -0.305054)
			(end -0.12065 -0.305054)
			(stroke
				(width 0.1)
				(type default)
			)
			(layer "F.Fab")
		)
		(fp_line
			(start -0.67945 0.3048)
			(end -0.67945 -0.305054)
			(stroke
				(width 0.1)
				(type default)
			)
			(layer "F.Fab")
		)
		(fp_line
			(start -0.12065 -0.305054)
			(end -0.12065 -0.2794)
			(stroke
				(width 0.1)
				(type default)
			)
			(layer "F.Fab")
		)
		(fp_line
			(start -0.12065 -0.2794)
			(end 0.12065 -0.2794)
			(stroke
				(width 0.1)
				(type default)
			)
			(layer "F.Fab")
		)
		(fp_line
			(start -0.12065 0.2794)
			(end -0.12065 0.3048)
			(stroke
				(width 0.1)
				(type default)
			)
			(layer "F.Fab")
		)
		(fp_line
			(start -0.12065 0.3048)
			(end -0.67945 0.3048)
			(stroke
				(width 0.1)
				(type default)
			)
			(layer "F.Fab")
		)
		(fp_line
			(start 0.120396 0.2794)
			(end -0.12065 0.2794)
			(stroke
				(width 0.1)
				(type default)
			)
			(layer "F.Fab")
		)
		(fp_line
			(start 0.120396 0.3048)
			(end 0.120396 0.2794)
			(stroke
				(width 0.1)
				(type default)
			)
			(layer "F.Fab")
		)
		(fp_line
			(start 0.12065 -0.3048)
			(end 0.67945 -0.3048)
			(stroke
				(width 0.1)
				(type default)
			)
			(layer "F.Fab")
		)
		(fp_line
			(start 0.12065 -0.2794)
			(end 0.12065 -0.3048)
			(stroke
				(width 0.1)
				(type default)
			)
			(layer "F.Fab")
		)
		(fp_line
			(start 0.67945 -0.3048)
			(end 0.67945 0.3048)
			(stroke
				(width 0.1)
				(type default)
			)
			(layer "F.Fab")
		)
		(fp_line
			(start 0.67945 0.3048)
			(end 0.120396 0.3048)
			(stroke
				(width 0.1)
				(type default)
			)
			(layer "F.Fab")
		)
		(pad "1" smd circle
			(at -0.40005 0)
			(size 0 0)
			(layers "F.Cu" "F.Mask" "F.Paste")
			(net "PVNN_MAIN_CPU0")
		)
		(pad "2" smd circle
			(at 0.40005 0)
			(size 0 0)
			(layers "F.Cu" "F.Mask" "F.Paste")
			(net "GND")
		)
	)
	(footprint ""
		(layer "F.Cu")
		(at 125.264926 -122.096784 90)
		(property "Reference" "R937"
			(at 0 0 90)
			(layer "F.SilkS")
			(hide yes)
			(effects
				(font
					(size 1.27 1.27)
				)
			)
		)
		(property "Value" ""
			(at 0 0 90)
			(layer "F.Fab")
			(effects
				(font
					(size 1.27 1.27)
				)
			)
		)
		(duplicate_pad_numbers_are_jumpers no)
		(fp_line
			(start 0.7874 -0.4064)
			(end 0.7874 0.4064)
			(stroke
				(width 0.1524)
				(type default)
			)
			(layer "F.SilkS")
		)
		(fp_line
			(start -0.7874 -0.4064)
			(end 0.7874 -0.4064)
			(stroke
				(width 0.1524)
				(type default)
			)
			(layer "F.SilkS")
		)
		(fp_line
			(start 0.7874 0.4064)
			(end -0.7874 0.4064)
			(stroke
				(width 0.1524)
				(type default)
			)
			(layer "F.SilkS")
		)
		(fp_line
			(start -0.7874 0.4064)
			(end -0.7874 -0.4064)
			(stroke
				(width 0.1524)
				(type default)
			)
			(layer "F.SilkS")
		)
		(fp_line
			(start -0.12065 -0.305054)
			(end -0.12065 -0.2794)
			(stroke
				(width 0.1)
				(type default)
			)
			(layer "F.Fab")
		)
		(fp_line
			(start -0.67945 -0.305054)
			(end -0.12065 -0.305054)
			(stroke
				(width 0.1)
				(type default)
			)
			(layer "F.Fab")
		)
		(fp_line
			(start 0.67945 -0.3048)
			(end 0.67945 0.3048)
			(stroke
				(width 0.1)
				(type default)
			)
			(layer "F.Fab")
		)
		(fp_line
			(start 0.12065 -0.3048)
			(end 0.67945 -0.3048)
			(stroke
				(width 0.1)
				(type default)
			)
			(layer "F.Fab")
		)
		(fp_line
			(start 0.12065 -0.2794)
			(end 0.12065 -0.3048)
			(stroke
				(width 0.1)
				(type default)
			)
			(layer "F.Fab")
		)
		(fp_line
			(start -0.12065 -0.2794)
			(end 0.12065 -0.2794)
			(stroke
				(width 0.1)
				(type default)
			)
			(layer "F.Fab")
		)
		(fp_line
			(start 0.120396 0.2794)
			(end -0.12065 0.2794)
			(stroke
				(width 0.1)
				(type default)
			)
			(layer "F.Fab")
		)
		(fp_line
			(start -0.12065 0.2794)
			(end -0.12065 0.3048)
			(stroke
				(width 0.1)
				(type default)
			)
			(layer "F.Fab")
		)
		(fp_line
			(start 0.67945 0.3048)
			(end 0.120396 0.3048)
			(stroke
				(width 0.1)
				(type default)
			)
			(layer "F.Fab")
		)
		(fp_line
			(start 0.120396 0.3048)
			(end 0.120396 0.2794)
			(stroke
				(width 0.1)
				(type default)
			)
			(layer "F.Fab")
		)
		(fp_line
			(start -0.12065 0.3048)
			(end -0.67945 0.3048)
			(stroke
				(width 0.1)
				(type default)
			)
			(layer "F.Fab")
		)
		(fp_line
			(start -0.67945 0.3048)
			(end -0.67945 -0.305054)
			(stroke
				(width 0.1)
				(type default)
			)
			(layer "F.Fab")
		)
		(pad "1" smd circle
			(at -0.40005 0 90)
			(size 0 0)
			(layers "F.Cu" "F.Mask" "F.Paste")
			(net "RST_CPU1_DRAM_EF_N")
		)
		(pad "2" smd circle
			(at 0.40005 0 90)
			(size 0 0)
			(layers "F.Cu" "F.Mask" "F.Paste")
			(net "GND")
		)
	)
	(footprint ""
		(layer "F.Cu")
		(at 128.516634 -408.517344 -90)
		(property "Reference" "C1521"
			(at 0 0 270)
			(layer "F.SilkS")
			(hide yes)
			(effects
				(font
					(size 1.27 1.27)
				)
			)
		)
		(property "Value" ""
			(at 0 0 270)
			(layer "F.Fab")
			(effects
				(font
					(size 1.27 1.27)
				)
			)
		)
		(duplicate_pad_numbers_are_jumpers no)
		(fp_line
			(start -0.299974 0.150114)
			(end -0.299974 -0.150114)
			(stroke
				(width 0.1)
				(type default)
			)
			(layer "F.Fab")
		)
		(fp_line
			(start 0.299974 0.150114)
			(end -0.299974 0.150114)
			(stroke
				(width 0.1)
				(type default)
			)
			(layer "F.Fab")
		)
		(fp_line
			(start -0.299974 -0.150114)
			(end 0.299974 -0.150114)
			(stroke
				(width 0.1)
				(type default)
			)
			(layer "F.Fab")
		)
		(fp_line
			(start 0.299974 -0.150114)
			(end 0.299974 0.150114)
			(stroke
				(width 0.1)
				(type default)
			)
			(layer "F.Fab")
		)
		(pad "1" smd rect
			(at -0.2667 0 270)
			(size 0.3048 0.381)
			(layers "F.Cu" "F.Mask" "F.Paste")
			(net "P5E_CPU1_PE3_TX_C_DP<13>")
		)
		(pad "2" smd rect
			(at 0.2667 0 270)
			(size 0.3048 0.381)
			(layers "F.Cu" "F.Mask" "F.Paste")
			(net "P5E_CPU1_PE3_TX_DP<13>")
		)
	)
	(footprint ""
		(layer "F.Cu")
		(at 234.885738 -119.183658 -90)
		(property "Reference" "R3195"
			(at 0 0 270)
			(layer "F.SilkS")
			(hide yes)
			(effects
				(font
					(size 1.27 1.27)
				)
			)
		)
		(property "Value" ""
			(at 0 0 270)
			(layer "F.Fab")
			(effects
				(font
					(size 1.27 1.27)
				)
			)
		)
		(duplicate_pad_numbers_are_jumpers no)
		(fp_line
			(start 0.410718 0.4064)
			(end -0.363982 0.4064)
			(stroke
				(width 0.1524)
				(type default)
			)
			(layer "F.SilkS")
		)
		(fp_line
			(start -0.7874 0.105918)
			(end -0.7874 -0.4064)
			(stroke
				(width 0.1524)
				(type default)
			)
			(layer "F.SilkS")
		)
		(fp_line
			(start -0.7874 -0.4064)
			(end 0.7874 -0.4064)
			(stroke
				(width 0.1524)
				(type default)
			)
			(layer "F.SilkS")
		)
		(fp_line
			(start 0.7874 -0.4064)
			(end 0.7874 0.123698)
			(stroke
				(width 0.1524)
				(type default)
			)
			(layer "F.SilkS")
		)
		(fp_line
			(start -0.67945 0.3048)
			(end -0.67945 -0.305054)
			(stroke
				(width 0.1)
				(type default)
			)
			(layer "F.Fab")
		)
		(fp_line
			(start -0.12065 0.3048)
			(end -0.67945 0.3048)
			(stroke
				(width 0.1)
				(type default)
			)
			(layer "F.Fab")
		)
		(fp_line
			(start 0.120396 0.3048)
			(end 0.120396 0.2794)
			(stroke
				(width 0.1)
				(type default)
			)
			(layer "F.Fab")
		)
		(fp_line
			(start 0.67945 0.3048)
			(end 0.120396 0.3048)
			(stroke
				(width 0.1)
				(type default)
			)
			(layer "F.Fab")
		)
		(fp_line
			(start -0.12065 0.2794)
			(end -0.12065 0.3048)
			(stroke
				(width 0.1)
				(type default)
			)
			(layer "F.Fab")
		)
		(fp_line
			(start 0.120396 0.2794)
			(end -0.12065 0.2794)
			(stroke
				(width 0.1)
				(type default)
			)
			(layer "F.Fab")
		)
		(fp_line
			(start -0.12065 -0.2794)
			(end 0.12065 -0.2794)
			(stroke
				(width 0.1)
				(type default)
			)
			(layer "F.Fab")
		)
		(fp_line
			(start 0.12065 -0.2794)
			(end 0.12065 -0.3048)
			(stroke
				(width 0.1)
				(type default)
			)
			(layer "F.Fab")
		)
		(fp_line
			(start 0.12065 -0.3048)
			(end 0.67945 -0.3048)
			(stroke
				(width 0.1)
				(type default)
			)
			(layer "F.Fab")
		)
		(fp_line
			(start 0.67945 -0.3048)
			(end 0.67945 0.3048)
			(stroke
				(width 0.1)
				(type default)
			)
			(layer "F.Fab")
		)
		(fp_line
			(start -0.67945 -0.305054)
			(end -0.12065 -0.305054)
			(stroke
				(width 0.1)
				(type default)
			)
			(layer "F.Fab")
		)
		(fp_line
			(start -0.12065 -0.305054)
			(end -0.12065 -0.2794)
			(stroke
				(width 0.1)
				(type default)
			)
			(layer "F.Fab")
		)
		(pad "1" smd circle
			(at -0.40005 0 270)
			(size 0 0)
			(layers "F.Cu" "F.Mask" "F.Paste")
			(net "CLK_100M_OCP_V3_2_A_R_DN")
		)
		(pad "2" smd circle
			(at 0.40005 0 270)
			(size 0 0)
			(layers "F.Cu" "F.Mask" "F.Paste")
			(net "CLK_100M_OCP_V3_2_A_DN")
		)
	)
	(footprint ""
		(layer "F.Cu")
		(at 440.50966 -106.38536 90)
		(property "Reference" "R4750"
			(at 0 0 90)
			(layer "F.SilkS")
			(hide yes)
			(effects
				(font
					(size 1.27 1.27)
				)
			)
		)
		(property "Value" ""
			(at 0 0 90)
			(layer "F.Fab")
			(effects
				(font
					(size 1.27 1.27)
				)
			)
		)
		(duplicate_pad_numbers_are_jumpers no)
		(fp_line
			(start 0.7874 -0.4064)
			(end 0.7874 0.4064)
			(stroke
				(width 0.1524)
				(type default)
			)
			(layer "F.SilkS")
		)
		(fp_line
			(start -0.7874 -0.4064)
			(end 0.7874 -0.4064)
			(stroke
				(width 0.1524)
				(type default)
			)
			(layer "F.SilkS")
		)
		(fp_line
			(start 0.7874 0.4064)
			(end -0.7874 0.4064)
			(stroke
				(width 0.1524)
				(type default)
			)
			(layer "F.SilkS")
		)
		(fp_line
			(start -0.7874 0.4064)
			(end -0.7874 -0.4064)
			(stroke
				(width 0.1524)
				(type default)
			)
			(layer "F.SilkS")
		)
		(fp_line
			(start -0.12065 -0.305054)
			(end -0.12065 -0.2794)
			(stroke
				(width 0.1)
				(type default)
			)
			(layer "F.Fab")
		)
		(fp_line
			(start -0.67945 -0.305054)
			(end -0.12065 -0.305054)
			(stroke
				(width 0.1)
				(type default)
			)
			(layer "F.Fab")
		)
		(fp_line
			(start 0.67945 -0.3048)
			(end 0.67945 0.3048)
			(stroke
				(width 0.1)
				(type default)
			)
			(layer "F.Fab")
		)
		(fp_line
			(start 0.12065 -0.3048)
			(end 0.67945 -0.3048)
			(stroke
				(width 0.1)
				(type default)
			)
			(layer "F.Fab")
		)
		(fp_line
			(start 0.12065 -0.2794)
			(end 0.12065 -0.3048)
			(stroke
				(width 0.1)
				(type default)
			)
			(layer "F.Fab")
		)
		(fp_line
			(start -0.12065 -0.2794)
			(end 0.12065 -0.2794)
			(stroke
				(width 0.1)
				(type default)
			)
			(layer "F.Fab")
		)
		(fp_line
			(start 0.120396 0.2794)
			(end -0.12065 0.2794)
			(stroke
				(width 0.1)
				(type default)
			)
			(layer "F.Fab")
		)
		(fp_line
			(start -0.12065 0.2794)
			(end -0.12065 0.3048)
			(stroke
				(width 0.1)
				(type default)
			)
			(layer "F.Fab")
		)
		(fp_line
			(start 0.67945 0.3048)
			(end 0.120396 0.3048)
			(stroke
				(width 0.1)
				(type default)
			)
			(layer "F.Fab")
		)
		(fp_line
			(start 0.120396 0.3048)
			(end 0.120396 0.2794)
			(stroke
				(width 0.1)
				(type default)
			)
			(layer "F.Fab")
		)
		(fp_line
			(start -0.12065 0.3048)
			(end -0.67945 0.3048)
			(stroke
				(width 0.1)
				(type default)
			)
			(layer "F.Fab")
		)
		(fp_line
			(start -0.67945 0.3048)
			(end -0.67945 -0.305054)
			(stroke
				(width 0.1)
				(type default)
			)
			(layer "F.Fab")
		)
		(pad "1" smd circle
			(at -0.40005 0 90)
			(size 0 0)
			(layers "F.Cu" "F.Mask" "F.Paste")
			(net "OCP_SFF_AUX_PWR_EN_R2")
		)
		(pad "2" smd circle
			(at 0.40005 0 90)
			(size 0 0)
			(layers "F.Cu" "F.Mask" "F.Paste")
			(net "OCP_SFF_AUX_PWR_EN")
		)
	)
	(footprint ""
		(layer "F.Cu")
		(at 15.508478 -16.099536 90)
		(property "Reference" "C807"
			(at 0 0 90)
			(layer "F.SilkS")
			(hide yes)
			(effects
				(font
					(size 1.27 1.27)
				)
			)
		)
		(property "Value" ""
			(at 0 0 90)
			(layer "F.Fab")
			(effects
				(font
					(size 1.27 1.27)
				)
			)
		)
		(duplicate_pad_numbers_are_jumpers no)
		(fp_line
			(start 0.299974 -0.150114)
			(end 0.299974 0.150114)
			(stroke
				(width 0.1)
				(type default)
			)
			(layer "F.Fab")
		)
		(fp_line
			(start -0.299974 -0.150114)
			(end 0.299974 -0.150114)
			(stroke
				(width 0.1)
				(type default)
			)
			(layer "F.Fab")
		)
		(fp_line
			(start 0.299974 0.150114)
			(end -0.299974 0.150114)
			(stroke
				(width 0.1)
				(type default)
			)
			(layer "F.Fab")
		)
		(fp_line
			(start -0.299974 0.150114)
			(end -0.299974 -0.150114)
			(stroke
				(width 0.1)
				(type default)
			)
			(layer "F.Fab")
		)
		(pad "1" smd rect
			(at -0.2667 0 90)
			(size 0.3048 0.381)
			(layers "F.Cu" "F.Mask" "F.Paste")
			(net "P5E_CPU1_PE1_TX_C_DP<15>")
		)
		(pad "2" smd rect
			(at 0.2667 0 90)
			(size 0.3048 0.381)
			(layers "F.Cu" "F.Mask" "F.Paste")
			(net "P5E_CPU1_PE1_TX_DP<15>")
		)
	)
	(footprint ""
		(layer "F.Cu")
		(at 127.69088 -92.674948 90)
		(property "Reference" "R242"
			(at 0 0 90)
			(layer "F.SilkS")
			(hide yes)
			(effects
				(font
					(size 1.27 1.27)
				)
			)
		)
		(property "Value" ""
			(at 0 0 90)
			(layer "F.Fab")
			(effects
				(font
					(size 1.27 1.27)
				)
			)
		)
		(duplicate_pad_numbers_are_jumpers no)
		(fp_line
			(start 0.7874 -0.4064)
			(end 0.7874 0.4064)
			(stroke
				(width 0.1524)
				(type default)
			)
			(layer "F.SilkS")
		)
		(fp_line
			(start -0.7874 -0.4064)
			(end 0.7874 -0.4064)
			(stroke
				(width 0.1524)
				(type default)
			)
			(layer "F.SilkS")
		)
		(fp_line
			(start 0.7874 0.4064)
			(end -0.7874 0.4064)
			(stroke
				(width 0.1524)
				(type default)
			)
			(layer "F.SilkS")
		)
		(fp_line
			(start -0.7874 0.4064)
			(end -0.7874 -0.4064)
			(stroke
				(width 0.1524)
				(type default)
			)
			(layer "F.SilkS")
		)
		(fp_line
			(start -0.12065 -0.305054)
			(end -0.12065 -0.2794)
			(stroke
				(width 0.1)
				(type default)
			)
			(layer "F.Fab")
		)
		(fp_line
			(start -0.67945 -0.305054)
			(end -0.12065 -0.305054)
			(stroke
				(width 0.1)
				(type default)
			)
			(layer "F.Fab")
		)
		(fp_line
			(start 0.67945 -0.3048)
			(end 0.67945 0.3048)
			(stroke
				(width 0.1)
				(type default)
			)
			(layer "F.Fab")
		)
		(fp_line
			(start 0.12065 -0.3048)
			(end 0.67945 -0.3048)
			(stroke
				(width 0.1)
				(type default)
			)
			(layer "F.Fab")
		)
		(fp_line
			(start 0.12065 -0.2794)
			(end 0.12065 -0.3048)
			(stroke
				(width 0.1)
				(type default)
			)
			(layer "F.Fab")
		)
		(fp_line
			(start -0.12065 -0.2794)
			(end 0.12065 -0.2794)
			(stroke
				(width 0.1)
				(type default)
			)
			(layer "F.Fab")
		)
		(fp_line
			(start 0.120396 0.2794)
			(end -0.12065 0.2794)
			(stroke
				(width 0.1)
				(type default)
			)
			(layer "F.Fab")
		)
		(fp_line
			(start -0.12065 0.2794)
			(end -0.12065 0.3048)
			(stroke
				(width 0.1)
				(type default)
			)
			(layer "F.Fab")
		)
		(fp_line
			(start 0.67945 0.3048)
			(end 0.120396 0.3048)
			(stroke
				(width 0.1)
				(type default)
			)
			(layer "F.Fab")
		)
		(fp_line
			(start 0.120396 0.3048)
			(end 0.120396 0.2794)
			(stroke
				(width 0.1)
				(type default)
			)
			(layer "F.Fab")
		)
		(fp_line
			(start -0.12065 0.3048)
			(end -0.67945 0.3048)
			(stroke
				(width 0.1)
				(type default)
			)
			(layer "F.Fab")
		)
		(fp_line
			(start -0.67945 0.3048)
			(end -0.67945 -0.305054)
			(stroke
				(width 0.1)
				(type default)
			)
			(layer "F.Fab")
		)
		(pad "1" smd circle
			(at -0.40005 0 90)
			(size 0 0)
			(layers "F.Cu" "F.Mask" "F.Paste")
			(net "P3V3")
		)
		(pad "2" smd circle
			(at 0.40005 0 90)
			(size 0 0)
			(layers "F.Cu" "F.Mask" "F.Paste")
			(net "H_CPU1_THERMTRIP_VT_N")
		)
	)
)
